#ISCELL
  pure_quanta quanta_title_block_c *
  *
#ISCELL
  pure_quanta_power cad_note *
  *
#CELL
  pure_quanta genoa_sp5 *
  page14_i159
#ISCELL
  mstr_standard offpage *
  page14_i160
#ISCELL
  mstr_standard offpage *
  page14_i161
#ISCELL
  mstr_standard tap *
  page14_i162
#ISCELL
  mstr_standard tap *
  page14_i163
#ISCELL
  mstr_standard tap *
  page14_i164
#ISCELL
  mstr_standard tap *
  page14_i165
#ISCELL
  mstr_standard tap *
  page14_i166
#ISCELL
  mstr_standard tap *
  page14_i167
#ISCELL
  mstr_standard tap *
  page14_i168
#ISCELL
  mstr_standard tap *
  page14_i169
#ISCELL
  mstr_standard tap *
  page14_i170
#ISCELL
  mstr_standard tap *
  page14_i171
#ISCELL
  mstr_standard tap *
  page14_i172
#ISCELL
  mstr_standard tap *
  page14_i173
#ISCELL
  mstr_standard tap *
  page14_i174
#ISCELL
  mstr_standard tap *
  page14_i175
#ISCELL
  mstr_standard tap *
  page14_i176
#ISCELL
  mstr_standard tap *
  page14_i177
#ISCELL
  mstr_standard tap *
  page14_i178
#ISCELL
  mstr_standard tap *
  page14_i179
#ISCELL
  mstr_standard tap *
  page14_i180
#ISCELL
  mstr_standard tap *
  page14_i181
#ISCELL
  mstr_standard tap *
  page14_i182
#ISCELL
  mstr_standard tap *
  page14_i183
#ISCELL
  mstr_standard tap *
  page14_i184
#ISCELL
  mstr_standard tap *
  page14_i185
#ISCELL
  mstr_standard tap *
  page14_i186
#ISCELL
  mstr_standard tap *
  page14_i187
#ISCELL
  mstr_standard tap *
  page14_i188
#ISCELL
  mstr_standard tap *
  page14_i189
#ISCELL
  mstr_standard tap *
  page14_i190
#ISCELL
  mstr_standard tap *
  page14_i191
#ISCELL
  mstr_standard tap *
  page14_i192
#ISCELL
  mstr_standard tap *
  page14_i193
#ISCELL
  mstr_standard tap *
  page14_i194
#ISCELL
  mstr_standard tap *
  page14_i195
#ISCELL
  mstr_standard tap *
  page14_i196
#ISCELL
  mstr_standard tap *
  page14_i197
#ISCELL
  mstr_standard offpage *
  page14_i198
#ISCELL
  mstr_standard tap *
  page14_i199
#ISCELL
  mstr_standard tap *
  page14_i200
#ISCELL
  mstr_standard tap *
  page14_i201
#ISCELL
  mstr_standard tap *
  page14_i202
#ISCELL
  mstr_standard tap *
  page14_i203
#ISCELL
  mstr_standard tap *
  page14_i204
#ISCELL
  mstr_standard tap *
  page14_i205
#ISCELL
  mstr_standard tap *
  page14_i206
#ISCELL
  mstr_standard tap *
  page14_i207
#ISCELL
  mstr_standard tap *
  page14_i208
#ISCELL
  mstr_standard tap *
  page14_i209
#ISCELL
  mstr_standard tap *
  page14_i210
#ISCELL
  mstr_standard tap *
  page14_i211
#ISCELL
  mstr_standard tap *
  page14_i212
#ISCELL
  mstr_standard tap *
  page14_i213
#ISCELL
  mstr_standard tap *
  page14_i214
#ISCELL
  mstr_standard tap *
  page14_i215
#ISCELL
  mstr_standard tap *
  page14_i216
#ISCELL
  mstr_standard tap *
  page14_i217
#ISCELL
  mstr_standard tap *
  page14_i218
#ISCELL
  mstr_standard tap *
  page14_i219
#ISCELL
  mstr_standard tap *
  page14_i220
#ISCELL
  mstr_standard tap *
  page14_i221
#ISCELL
  mstr_standard tap *
  page14_i222
#ISCELL
  mstr_standard tap *
  page14_i223
#ISCELL
  mstr_standard tap *
  page14_i224
#ISCELL
  mstr_standard tap *
  page14_i225
#ISCELL
  mstr_standard tap *
  page14_i226
#ISCELL
  mstr_standard tap *
  page14_i227
#ISCELL
  mstr_standard tap *
  page14_i228
#ISCELL
  mstr_standard tap *
  page14_i229
#ISCELL
  mstr_standard tap *
  page14_i230
#ISCELL
  mstr_standard tap *
  page14_i231
#ISCELL
  mstr_standard tap *
  page14_i232
#ISCELL
  mstr_standard tap *
  page14_i233
#ISCELL
  mstr_standard tap *
  page14_i234
#ISCELL
  mstr_standard offpage *
  page14_i235
#ISCELL
  mstr_standard tap *
  page14_i236
#ISCELL
  mstr_standard tap *
  page14_i237
#ISCELL
  mstr_standard tap *
  page14_i238
#ISCELL
  mstr_standard tap *
  page14_i239
#ISCELL
  mstr_standard tap *
  page14_i240
#ISCELL
  mstr_standard tap *
  page14_i241
#ISCELL
  mstr_standard tap *
  page14_i242
#ISCELL
  mstr_standard tap *
  page14_i243
#ISCELL
  mstr_standard tap *
  page14_i244
#ISCELL
  mstr_standard tap *
  page14_i245
#ISCELL
  mstr_standard tap *
  page14_i246
#ISCELL
  mstr_standard tap *
  page14_i247
#ISCELL
  mstr_standard tap *
  page14_i248
#ISCELL
  mstr_standard tap *
  page14_i249
#ISCELL
  mstr_standard tap *
  page14_i250
#ISCELL
  mstr_standard tap *
  page14_i251
#ISCELL
  mstr_standard tap *
  page14_i252
#ISCELL
  mstr_standard tap *
  page14_i253
#ISCELL
  mstr_standard tap *
  page14_i254
#ISCELL
  mstr_standard tap *
  page14_i255
#ISCELL
  mstr_standard tap *
  page14_i256
#ISCELL
  mstr_standard tap *
  page14_i257
#ISCELL
  mstr_standard tap *
  page14_i258
#ISCELL
  mstr_standard tap *
  page14_i259
#ISCELL
  mstr_standard tap *
  page14_i260
#ISCELL
  mstr_standard tap *
  page14_i261
#ISCELL
  mstr_standard tap *
  page14_i262
#ISCELL
  mstr_standard tap *
  page14_i263
#ISCELL
  mstr_standard tap *
  page14_i264
#ISCELL
  mstr_standard tap *
  page14_i265
#ISCELL
  mstr_standard tap *
  page14_i266
#ISCELL
  mstr_standard tap *
  page14_i267
#ISCELL
  mstr_standard tap *
  page14_i268
#ISCELL
  mstr_standard tap *
  page14_i269
#ISCELL
  mstr_standard tap *
  page14_i270
#ISCELL
  mstr_standard tap *
  page14_i271
#ISCELL
  mstr_standard tap *
  page14_i272
#ISCELL
  mstr_standard tap *
  page14_i273
#ISCELL
  mstr_standard tap *
  page14_i274
#ISCELL
  mstr_standard tap *
  page14_i275
#ISCELL
  mstr_standard tap *
  page14_i276
#ISCELL
  mstr_standard tap *
  page14_i277
#ISCELL
  mstr_standard tap *
  page14_i278
#ISCELL
  mstr_standard tap *
  page14_i279
#ISCELL
  mstr_standard tap *
  page14_i280
#ISCELL
  mstr_standard tap *
  page14_i281
#ISCELL
  mstr_standard tap *
  page14_i282
#ISCELL
  standard offpage *
  page14_i283
#ISCELL
  standard offpage *
  page14_i284
#ISCELL
  standard offpage *
  page14_i285
#ISCELL
  standard offpage *
  page14_i286
#ISCELL
  mstr_standard tap *
  page14_i287
#ISCELL
  mstr_standard tap *
  page14_i288
#ISCELL
  mstr_standard tap *
  page14_i289
#ISCELL
  mstr_standard tap *
  page14_i290
#ISCELL
  mstr_standard tap *
  page14_i291
#ISCELL
  mstr_standard tap *
  page14_i292
#ISCELL
  mstr_standard tap *
  page14_i293
#ISCELL
  mstr_standard tap *
  page14_i294
#ISCELL
  mstr_standard tap *
  page14_i295
#ISCELL
  mstr_standard tap *
  page14_i296
#ISCELL
  mstr_standard tap *
  page14_i297
#ISCELL
  mstr_standard tap *
  page14_i298
#ISCELL
  mstr_standard tap *
  page14_i299
#ISCELL
  mstr_standard tap *
  page14_i300
#ISCELL
  mstr_standard tap *
  page14_i301
#ISCELL
  standard offpage *
  page14_i302
#ISCELL
  standard offpage *
  page14_i303
#ISCELL
  standard offpage *
  page14_i304
#ISCELL
  standard offpage *
  page14_i305
#ISCELL
  standard offpage *
  page14_i306
#ISCELL
  standard offpage *
  page14_i307
#ISCELL
  standard offpage *
  page14_i308
#ISCELL
  standard offpage *
  page14_i309
#ISCELL
  standard offpage *
  page14_i310
#ISCELL
  standard offpage *
  page14_i311
#ISCELL
  mstr_standard offpage *
  page14_i312
#ISCELL
  standard offpage *
  page14_i313
#ISCELL
  standard offpage *
  page14_i314
#CELL
  pure_quanta q_res *
  page14_i315
#ISCELL
  mstr_standard offpage *
  page14_i316
